(kicad_pcb
	(version 20241229)
	(generator "pcbnew")
	(generator_version "9.0")
	(general
		(thickness 1.599998)
		(legacy_teardrops no)
	)
	(paper "A4")
	(title_block
		(date "2023-02-12")
		(rev "1.1.5")
		(comment 9 "footprints 62-68 of 473")
	)
	(layers
		(0 "F.Cu" signal)
		(4 "In1.Cu" power "In1.GND")
		(6 "In2.Cu" signal)
		(8 "In3.Cu" power "In3.GND")
		(10 "In4.Cu" power "In4.VCC")
		(12 "In5.Cu" signal)
		(14 "In6.Cu" power "In6.VCC")
		(2 "B.Cu" signal)
		(9 "F.Adhes" user "F.Adhesive")
		(11 "B.Adhes" user "B.Adhesive")
		(13 "F.Paste" user)
		(15 "B.Paste" user)
		(5 "F.SilkS" user "F.Silkscreen")
		(7 "B.SilkS" user "B.Silkscreen")
		(1 "F.Mask" user)
		(3 "B.Mask" user)
		(17 "Dwgs.User" user "User.Drawings")
		(19 "Cmts.User" user "User.Comments")
		(21 "Eco1.User" user "User.Eco1")
		(23 "Eco2.User" user "User.Eco2")
		(25 "Edge.Cuts" user)
		(27 "Margin" user)
		(31 "F.CrtYd" user "F.Courtyard")
		(29 "B.CrtYd" user "B.Courtyard")
		(35 "F.Fab" user)
		(33 "B.Fab" user)
	)
	(footprint "antmicro-footprints:R_0402_1005Metric"
		(layer "F.Cu")
		(at 202.386328 86.620008 180)
		(descr "Resistor SMD 0402")
		(tags "resistor SMD 0402")
		(property "Reference" "R58"
			(at 0.886328 -1.279992 180)
			(layer "F.SilkS")
			(effects
				(font
					(size 0.7 0.7)
					(thickness 0.15)
				)
				(justify left bottom)
			)
		)
		(property "Value" "R_330R_0402"
			(at 0 1.4 180)
			(layer "F.Fab")
			(effects
				(font
					(size 0.7 0.7)
					(thickness 0.15)
				)
				(justify left bottom)
			)
		)
		(property "Description" "330R resistor in 0402 package with 1% tolerance"
			(at 0 0 180)
			(layer "F.Fab")
			(hide yes)
			(effects
				(font
					(size 1.27 1.27)
					(thickness 0.15)
				)
			)
		)
		(property "Author" "Antmicro"
			(at 404.772656 173.240016 0)
			(layer "F.Fab")
			(hide yes)
			(effects
				(font
					(size 1 1)
					(thickness 0.15)
				)
			)
		)
		(property "License" "Apache-2.0"
			(at 404.772656 173.240016 0)
			(layer "F.Fab")
			(hide yes)
			(effects
				(font
					(size 1 1)
					(thickness 0.15)
				)
			)
		)
		(property "MPN" "CR0402-FX-3300GLF"
			(at 404.772656 173.240016 0)
			(layer "F.Fab")
			(hide yes)
			(effects
				(font
					(size 1 1)
					(thickness 0.15)
				)
			)
		)
		(property "Manufacturer" "Bourns"
			(at 404.772656 173.240016 0)
			(layer "F.Fab")
			(hide yes)
			(effects
				(font
					(size 1 1)
					(thickness 0.15)
				)
			)
		)
		(property "Tolerance" "1%"
			(at 404.772656 173.240016 0)
			(layer "F.Fab")
			(hide yes)
			(effects
				(font
					(size 1 1)
					(thickness 0.15)
				)
			)
		)
		(property "Val" "330R"
			(at 404.772656 173.240016 0)
			(layer "F.Fab")
			(hide yes)
			(effects
				(font
					(size 1 1)
					(thickness 0.15)
				)
			)
		)
		(sheetname "Config SPI flash")
		(sheetfile "config-spi.kicad_sch")
		(attr smd)
		(fp_rect
			(start -0.93 -0.47)
			(end 0.93 0.47)
			(stroke
				(width 0.05)
				(type solid)
			)
			(fill no)
			(layer "F.CrtYd")
		)
		(fp_rect
			(start -0.5 -0.25)
			(end 0.5 0.25)
			(stroke
				(width 0.15)
				(type solid)
			)
			(fill no)
			(layer "F.Fab")
		)
		(pad "1" smd roundrect
			(at -0.485 0 180)
			(size 0.59 0.64)
			(layers "F.Cu" "F.Mask" "F.Paste")
			(roundrect_rratio 0.25)
			(net 67 "Net-(D9-Pad2)")
			(pintype "passive")
		)
		(pad "2" smd roundrect
			(at 0.485 0 180)
			(size 0.59 0.64)
			(layers "F.Cu" "F.Mask" "F.Paste")
			(roundrect_rratio 0.25)
			(net 233 "Net-(Q7-D)")
			(pintype "passive")
		)
	)
	(footprint "antmicro-footprints:R_0402_1005Metric"
		(layer "F.Cu")
		(at 213.686328 93.220008 180)
		(descr "Resistor SMD 0402")
		(tags "resistor SMD 0402")
		(property "Reference" "R67"
			(at 1.086328 0.520008 180)
			(layer "F.SilkS")
			(effects
				(font
					(size 0.7 0.7)
					(thickness 0.15)
				)
				(justify left bottom)
			)
		)
		(property "Value" "R_4k7_0402"
			(at 0 1.4 180)
			(layer "F.Fab")
			(effects
				(font
					(size 0.7 0.7)
					(thickness 0.15)
				)
				(justify left bottom)
			)
		)
		(property "Description" "4k7 resistor in 0402 package with 1% tolerance"
			(at 0 0 180)
			(layer "F.Fab")
			(hide yes)
			(effects
				(font
					(size 1.27 1.27)
					(thickness 0.15)
				)
			)
		)
		(property "Author" "Antmicro"
			(at 427.372656 186.440016 0)
			(layer "F.Fab")
			(hide yes)
			(effects
				(font
					(size 1 1)
					(thickness 0.15)
				)
			)
		)
		(property "License" "Apache-2.0"
			(at 427.372656 186.440016 0)
			(layer "F.Fab")
			(hide yes)
			(effects
				(font
					(size 1 1)
					(thickness 0.15)
				)
			)
		)
		(property "MPN" "CR0402-FX-4701GLF"
			(at 427.372656 186.440016 0)
			(layer "F.Fab")
			(hide yes)
			(effects
				(font
					(size 1 1)
					(thickness 0.15)
				)
			)
		)
		(property "Manufacturer" "Bourns"
			(at 427.372656 186.440016 0)
			(layer "F.Fab")
			(hide yes)
			(effects
				(font
					(size 1 1)
					(thickness 0.15)
				)
			)
		)
		(property "Tolerance" "1%"
			(at 427.372656 186.440016 0)
			(layer "F.Fab")
			(hide yes)
			(effects
				(font
					(size 1 1)
					(thickness 0.15)
				)
			)
		)
		(property "Val" "4k7"
			(at 427.372656 186.440016 0)
			(layer "F.Fab")
			(hide yes)
			(effects
				(font
					(size 1 1)
					(thickness 0.15)
				)
			)
		)
		(sheetname "Config SPI flash")
		(sheetfile "config-spi.kicad_sch")
		(attr smd)
		(fp_rect
			(start -0.93 -0.47)
			(end 0.93 0.47)
			(stroke
				(width 0.05)
				(type solid)
			)
			(fill no)
			(layer "F.CrtYd")
		)
		(fp_rect
			(start -0.5 -0.25)
			(end 0.5 0.25)
			(stroke
				(width 0.15)
				(type solid)
			)
			(fill no)
			(layer "F.Fab")
		)
		(pad "1" smd roundrect
			(at -0.485 0 180)
			(size 0.59 0.64)
			(layers "F.Cu" "F.Mask" "F.Paste")
			(roundrect_rratio 0.25)
			(net 459 "3V3_SYS")
			(pintype "passive")
		)
		(pad "2" smd roundrect
			(at 0.485 0 180)
			(size 0.59 0.64)
			(layers "F.Cu" "F.Mask" "F.Paste")
			(roundrect_rratio 0.25)
			(net 208 "PROGRAM_B")
			(pintype "passive")
		)
	)
	(footprint "antmicro-footprints:R_0402_1005Metric"
		(layer "F.Cu")
		(at 172.359 111.667 -90)
		(descr "Resistor SMD 0402")
		(tags "resistor SMD 0402")
		(property "Reference" "R61"
			(at -0.768 -0.3 270)
			(layer "F.SilkS")
			(effects
				(font
					(size 0.7 0.7)
					(thickness 0.15)
				)
				(justify left bottom)
			)
		)
		(property "Value" "R_100R_0402"
			(at 0 1.4 270)
			(layer "F.Fab")
			(effects
				(font
					(size 0.7 0.7)
					(thickness 0.15)
				)
				(justify left bottom)
			)
		)
		(property "Description" "100R resistor in 0402 package with 1% tolerance"
			(at 0 0 270)
			(layer "F.Fab")
			(hide yes)
			(effects
				(font
					(size 1.27 1.27)
					(thickness 0.15)
				)
			)
		)
		(property "Author" "Antmicro"
			(at 60.692 284.026 0)
			(layer "F.Fab")
			(hide yes)
			(effects
				(font
					(size 1 1)
					(thickness 0.15)
				)
			)
		)
		(property "License" "Apache-2.0"
			(at 60.692 284.026 0)
			(layer "F.Fab")
			(hide yes)
			(effects
				(font
					(size 1 1)
					(thickness 0.15)
				)
			)
		)
		(property "MPN" "CR0402-FX-1000GLF"
			(at 60.692 284.026 0)
			(layer "F.Fab")
			(hide yes)
			(effects
				(font
					(size 1 1)
					(thickness 0.15)
				)
			)
		)
		(property "Manufacturer" "Bourns"
			(at 60.692 284.026 0)
			(layer "F.Fab")
			(hide yes)
			(effects
				(font
					(size 1 1)
					(thickness 0.15)
				)
			)
		)
		(property "Tolerance" "1%"
			(at 60.692 284.026 0)
			(layer "F.Fab")
			(hide yes)
			(effects
				(font
					(size 1 1)
					(thickness 0.15)
				)
			)
		)
		(property "Val" "100R"
			(at 60.692 284.026 0)
			(layer "F.Fab")
			(hide yes)
			(effects
				(font
					(size 1 1)
					(thickness 0.15)
				)
			)
		)
		(sheetname "Config SPI flash")
		(sheetfile "config-spi.kicad_sch")
		(attr exclude_from_pos_files exclude_from_bom dnp)
		(fp_rect
			(start -0.93 -0.47)
			(end 0.93 0.47)
			(stroke
				(width 0.05)
				(type solid)
			)
			(fill no)
			(layer "F.CrtYd")
		)
		(fp_rect
			(start -0.5 -0.25)
			(end 0.5 0.25)
			(stroke
				(width 0.15)
				(type solid)
			)
			(fill no)
			(layer "F.Fab")
		)
		(pad "1" smd roundrect
			(at -0.485 0 270)
			(size 0.59 0.64)
			(layers "F.Cu" "F.Mask" "F.Paste")
			(roundrect_rratio 0.25)
			(net 95 "PUDC_B")
			(pintype "passive")
		)
		(pad "2" smd roundrect
			(at 0.485 0 270)
			(size 0.59 0.64)
			(layers "F.Cu" "F.Mask" "F.Paste")
			(roundrect_rratio 0.25)
			(net 5 "GND")
			(pintype "passive")
		)
	)
	(footprint "antmicro-footprints:R_0402_1005Metric"
		(layer "F.Cu")
		(at 197.486328 84.720008 90)
		(descr "Resistor SMD 0402")
		(tags "resistor SMD 0402")
		(property "Reference" "R68"
			(at -0.879992 -0.486328 90)
			(layer "F.SilkS")
			(effects
				(font
					(size 0.7 0.7)
					(thickness 0.15)
				)
				(justify left bottom)
			)
		)
		(property "Value" "R_330R_0402"
			(at 0 1.4 90)
			(layer "F.Fab")
			(effects
				(font
					(size 0.7 0.7)
					(thickness 0.15)
				)
				(justify left bottom)
			)
		)
		(property "Description" "330R resistor in 0402 package with 1% tolerance"
			(at 0 0 90)
			(layer "F.Fab")
			(hide yes)
			(effects
				(font
					(size 1.27 1.27)
					(thickness 0.15)
				)
			)
		)
		(property "Author" "Antmicro"
			(at 282.206336 -112.76632 0)
			(layer "F.Fab")
			(hide yes)
			(effects
				(font
					(size 1 1)
					(thickness 0.15)
				)
			)
		)
		(property "License" "Apache-2.0"
			(at 282.206336 -112.76632 0)
			(layer "F.Fab")
			(hide yes)
			(effects
				(font
					(size 1 1)
					(thickness 0.15)
				)
			)
		)
		(property "MPN" "CR0402-FX-3300GLF"
			(at 282.206336 -112.76632 0)
			(layer "F.Fab")
			(hide yes)
			(effects
				(font
					(size 1 1)
					(thickness 0.15)
				)
			)
		)
		(property "Manufacturer" "Bourns"
			(at 282.206336 -112.76632 0)
			(layer "F.Fab")
			(hide yes)
			(effects
				(font
					(size 1 1)
					(thickness 0.15)
				)
			)
		)
		(property "Tolerance" "1%"
			(at 282.206336 -112.76632 0)
			(layer "F.Fab")
			(hide yes)
			(effects
				(font
					(size 1 1)
					(thickness 0.15)
				)
			)
		)
		(property "Val" "330R"
			(at 282.206336 -112.76632 0)
			(layer "F.Fab")
			(hide yes)
			(effects
				(font
					(size 1 1)
					(thickness 0.15)
				)
			)
		)
		(sheetname "Config SPI flash")
		(sheetfile "config-spi.kicad_sch")
		(attr smd)
		(fp_rect
			(start -0.93 -0.47)
			(end 0.93 0.47)
			(stroke
				(width 0.05)
				(type solid)
			)
			(fill no)
			(layer "F.CrtYd")
		)
		(fp_rect
			(start -0.5 -0.25)
			(end 0.5 0.25)
			(stroke
				(width 0.15)
				(type solid)
			)
			(fill no)
			(layer "F.Fab")
		)
		(pad "1" smd roundrect
			(at -0.485 0 90)
			(size 0.59 0.64)
			(layers "F.Cu" "F.Mask" "F.Paste")
			(roundrect_rratio 0.25)
			(net 459 "3V3_SYS")
			(pintype "passive")
		)
		(pad "2" smd roundrect
			(at 0.485 0 90)
			(size 0.59 0.64)
			(layers "F.Cu" "F.Mask" "F.Paste")
			(roundrect_rratio 0.25)
			(net 21 "DONE")
			(pintype "passive")
		)
	)
	(footprint "antmicro-footprints:R_0402_1005Metric"
		(layer "F.Cu")
		(at 188.886328 92.720008 180)
		(descr "Resistor SMD 0402")
		(tags "resistor SMD 0402")
		(property "Reference" "R69"
			(at 1.086328 -1.279992 180)
			(layer "F.SilkS")
			(effects
				(font
					(size 0.7 0.7)
					(thickness 0.15)
				)
				(justify left bottom)
			)
		)
		(property "Value" "R_0R_0402"
			(at 0 1.4 180)
			(layer "F.Fab")
			(effects
				(font
					(size 0.7 0.7)
					(thickness 0.15)
				)
				(justify left bottom)
			)
		)
		(property "Description" "0R resistor in 0402 package with unspecified tolerance"
			(at 0 0 180)
			(layer "F.Fab")
			(hide yes)
			(effects
				(font
					(size 1.27 1.27)
					(thickness 0.15)
				)
			)
		)
		(property "Author" "Antmicro"
			(at 377.772656 185.440016 0)
			(layer "F.Fab")
			(hide yes)
			(effects
				(font
					(size 1 1)
					(thickness 0.15)
				)
			)
		)
		(property "Current" "1A"
			(at 377.772656 185.440016 0)
			(layer "F.Fab")
			(hide yes)
			(effects
				(font
					(size 1 1)
					(thickness 0.15)
				)
			)
		)
		(property "License" "Apache-2.0"
			(at 377.772656 185.440016 0)
			(layer "F.Fab")
			(hide yes)
			(effects
				(font
					(size 1 1)
					(thickness 0.15)
				)
			)
		)
		(property "MPN" "ERJ2GE0R00X"
			(at 377.772656 185.440016 0)
			(layer "F.Fab")
			(hide yes)
			(effects
				(font
					(size 1 1)
					(thickness 0.15)
				)
			)
		)
		(property "Manufacturer" "Panasonic"
			(at 377.772656 185.440016 0)
			(layer "F.Fab")
			(hide yes)
			(effects
				(font
					(size 1 1)
					(thickness 0.15)
				)
			)
		)
		(property "Tolerance" ""
			(at 377.772656 185.440016 0)
			(layer "F.Fab")
			(hide yes)
			(effects
				(font
					(size 1 1)
					(thickness 0.15)
				)
			)
		)
		(property "Val" "0R"
			(at 377.772656 185.440016 0)
			(layer "F.Fab")
			(hide yes)
			(effects
				(font
					(size 1 1)
					(thickness 0.15)
				)
			)
		)
		(sheetname "Config SPI flash")
		(sheetfile "config-spi.kicad_sch")
		(attr smd)
		(fp_rect
			(start -0.93 -0.47)
			(end 0.93 0.47)
			(stroke
				(width 0.05)
				(type solid)
			)
			(fill no)
			(layer "F.CrtYd")
		)
		(fp_rect
			(start -0.5 -0.25)
			(end 0.5 0.25)
			(stroke
				(width 0.15)
				(type solid)
			)
			(fill no)
			(layer "F.Fab")
		)
		(pad "1" smd roundrect
			(at -0.485 0 180)
			(size 0.59 0.64)
			(layers "F.Cu" "F.Mask" "F.Paste")
			(roundrect_rratio 0.25)
			(net 459 "3V3_SYS")
			(pintype "passive")
		)
		(pad "2" smd roundrect
			(at 0.485 0 180)
			(size 0.59 0.64)
			(layers "F.Cu" "F.Mask" "F.Paste")
			(roundrect_rratio 0.25)
			(net 219 "CFGBVS")
			(pintype "passive")
		)
	)
	(footprint "antmicro-footprints:R_0402_1005Metric"
		(layer "F.Cu")
		(at 180.1885 119.541)
		(descr "Resistor SMD 0402")
		(tags "resistor SMD 0402")
		(property "Reference" "R51"
			(at 0.8115 0.399 0)
			(layer "F.SilkS")
			(effects
				(font
					(size 0.7 0.7)
					(thickness 0.15)
				)
				(justify left bottom)
			)
		)
		(property "Value" "R_0R_0402"
			(at 0 1.4 0)
			(layer "F.Fab")
			(effects
				(font
					(size 0.7 0.7)
					(thickness 0.15)
				)
				(justify left bottom)
			)
		)
		(property "Description" "0R resistor in 0402 package with unspecified tolerance"
			(at 0 0 0)
			(layer "F.Fab")
			(hide yes)
			(effects
				(font
					(size 1.27 1.27)
					(thickness 0.15)
				)
			)
		)
		(property "Author" "Antmicro"
			(at 0 0 0)
			(layer "F.Fab")
			(hide yes)
			(effects
				(font
					(size 1 1)
					(thickness 0.15)
				)
			)
		)
		(property "Current" "1A"
			(at 0 0 0)
			(layer "F.Fab")
			(hide yes)
			(effects
				(font
					(size 1 1)
					(thickness 0.15)
				)
			)
		)
		(property "License" "Apache-2.0"
			(at 0 0 0)
			(layer "F.Fab")
			(hide yes)
			(effects
				(font
					(size 1 1)
					(thickness 0.15)
				)
			)
		)
		(property "MPN" "ERJ2GE0R00X"
			(at 0 0 0)
			(layer "F.Fab")
			(hide yes)
			(effects
				(font
					(size 1 1)
					(thickness 0.15)
				)
			)
		)
		(property "Manufacturer" "Panasonic"
			(at 0 0 0)
			(layer "F.Fab")
			(hide yes)
			(effects
				(font
					(size 1 1)
					(thickness 0.15)
				)
			)
		)
		(property "Tolerance" ""
			(at 0 0 0)
			(layer "F.Fab")
			(hide yes)
			(effects
				(font
					(size 1 1)
					(thickness 0.15)
				)
			)
		)
		(property "Val" "0R"
			(at 0 0 0)
			(layer "F.Fab")
			(hide yes)
			(effects
				(font
					(size 1 1)
					(thickness 0.15)
				)
			)
		)
		(sheetname "Config SPI flash")
		(sheetfile "config-spi.kicad_sch")
		(attr smd)
		(fp_rect
			(start -0.93 -0.47)
			(end 0.93 0.47)
			(stroke
				(width 0.05)
				(type solid)
			)
			(fill no)
			(layer "F.CrtYd")
		)
		(fp_rect
			(start -0.5 -0.25)
			(end 0.5 0.25)
			(stroke
				(width 0.15)
				(type solid)
			)
			(fill no)
			(layer "F.Fab")
		)
		(pad "1" smd roundrect
			(at -0.485 0)
			(size 0.59 0.64)
			(layers "F.Cu" "F.Mask" "F.Paste")
			(roundrect_rratio 0.25)
			(net 259 "Net-(U5-SI{slash}IO0)")
			(pintype "passive")
		)
		(pad "2" smd roundrect
			(at 0.485 0)
			(size 0.59 0.64)
			(layers "F.Cu" "F.Mask" "F.Paste")
			(roundrect_rratio 0.25)
			(net 15 "QSPI_DQ0")
			(pintype "passive")
		)
	)
	(footprint "antmicro-footprints:R_0402_1005Metric"
		(layer "F.Cu")
		(at 168.822 117.001 180)
		(descr "Resistor SMD 0402")
		(tags "resistor SMD 0402")
		(property "Reference" "R52"
			(at 1.322 -3.729 180)
			(layer "F.SilkS")
			(effects
				(font
					(size 0.7 0.7)
					(thickness 0.15)
				)
				(justify left bottom)
			)
		)
		(property "Value" "R_0R_0402"
			(at 0 1.4 180)
			(layer "F.Fab")
			(effects
				(font
					(size 0.7 0.7)
					(thickness 0.15)
				)
				(justify left bottom)
			)
		)
		(property "Description" "0R resistor in 0402 package with unspecified tolerance"
			(at 0 0 180)
			(layer "F.Fab")
			(hide yes)
			(effects
				(font
					(size 1.27 1.27)
					(thickness 0.15)
				)
			)
		)
		(property "Author" "Antmicro"
			(at 337.644 234.002 0)
			(layer "F.Fab")
			(hide yes)
			(effects
				(font
					(size 1 1)
					(thickness 0.15)
				)
			)
		)
		(property "Current" "1A"
			(at 337.644 234.002 0)
			(layer "F.Fab")
			(hide yes)
			(effects
				(font
					(size 1 1)
					(thickness 0.15)
				)
			)
		)
		(property "License" "Apache-2.0"
			(at 337.644 234.002 0)
			(layer "F.Fab")
			(hide yes)
			(effects
				(font
					(size 1 1)
					(thickness 0.15)
				)
			)
		)
		(property "MPN" "ERJ2GE0R00X"
			(at 337.644 234.002 0)
			(layer "F.Fab")
			(hide yes)
			(effects
				(font
					(size 1 1)
					(thickness 0.15)
				)
			)
		)
		(property "Manufacturer" "Panasonic"
			(at 337.644 234.002 0)
			(layer "F.Fab")
			(hide yes)
			(effects
				(font
					(size 1 1)
					(thickness 0.15)
				)
			)
		)
		(property "Tolerance" ""
			(at 337.644 234.002 0)
			(layer "F.Fab")
			(hide yes)
			(effects
				(font
					(size 1 1)
					(thickness 0.15)
				)
			)
		)
		(property "Val" "0R"
			(at 337.644 234.002 0)
			(layer "F.Fab")
			(hide yes)
			(effects
				(font
					(size 1 1)
					(thickness 0.15)
				)
			)
		)
		(sheetname "Config SPI flash")
		(sheetfile "config-spi.kicad_sch")
		(attr smd)
		(fp_rect
			(start -0.93 -0.47)
			(end 0.93 0.47)
			(stroke
				(width 0.05)
				(type solid)
			)
			(fill no)
			(layer "F.CrtYd")
		)
		(fp_rect
			(start -0.5 -0.25)
			(end 0.5 0.25)
			(stroke
				(width 0.15)
				(type solid)
			)
			(fill no)
			(layer "F.Fab")
		)
		(pad "1" smd roundrect
			(at -0.485 0 180)
			(size 0.59 0.64)
			(layers "F.Cu" "F.Mask" "F.Paste")
			(roundrect_rratio 0.25)
			(net 260 "Net-(U5-SO{slash}IO1)")
			(pintype "passive")
		)
		(pad "2" smd roundrect
			(at 0.485 0 180)
			(size 0.59 0.64)
			(layers "F.Cu" "F.Mask" "F.Paste")
			(roundrect_rratio 0.25)
			(net 16 "QSPI_DQ1")
			(pintype "passive")
		)
	)
)
